#ISCELL
  mstr_symbols intel_corp_bpage *
  *
#ISCELL
  mstr_standard offpage *
  page168_i1
#CELL
  mstr_discrete res *
  page168_i11
#ISCELL
  mstr_symbols gnd *
  page168_i14
#CELL
  mstr_discrete fet_n_dual *
  page168_i18
#CELL
  mstr_discrete fet_n_dual *
  page168_i19
#CELL
  mstr_discrete diode *
  page168_i2
#CELL
  mstr_discrete res *
  page168_i22
#ISCELL
  mstr_symbols p3v3_stby *
  page168_i24
#ISCELL
  mstr_symbols gnd *
  page168_i26
#ISCELL
  mstr_standard offpage *
  page168_i28
#ISCELL
  mstr_symbols p3v3_stby *
  page168_i29
#CELL
  mstr_discrete diode *
  page168_i3
#ISCELL
  mstr_standard offpage *
  page168_i31
#ISCELL
  mstr_symbols gnd *
  page168_i32
#CELL
  mstr_discrete res *
  page168_i33
#CELL
  mstr_discrete res *
  page168_i34
#ISCELL
  mstr_symbols p5v_stby *
  page168_i35
#ISCELL
  mstr_symbols gnd *
  page168_i36
#CELL
  mstr_discrete npn *
  page168_i37
#ISCELL
  mstr_symbols p3v3_stby *
  page168_i38
#CELL
  mstr_discrete res *
  page168_i39
#CELL
  mstr_discrete diode *
  page168_i4
#CELL
  mstr_discrete res *
  page168_i40
#CELL
  mstr_discrete fet_n *
  page168_i41
#CELL
  mstr_discrete diode *
  page168_i5
#CELL
  mstr_discrete res *
  page168_i6
#CELL
  mstr_discrete npn *
  page168_i8
